(kicad_pcb
	(version 20260206)
	(generator "pcbnew")
	(generator_version "10.0")
	(general
		(thickness 1.6)
		(legacy_teardrops no)
	)
	(paper "A4")
	(title_block
		(title "01162023_DA0F0TEBIF0_F0T_Expander_BD_F_brd_V02_OCP.brd")
		(comment 1 "Grand Teton / footprints 9442-9450 of 9728")
	)
	(layers
		(0 "F.Cu" signal "TOP")
		(4 "In1.Cu" signal "GND")
		(6 "In2.Cu" signal "VCC")
		(8 "In3.Cu" signal "VCC1")
		(10 "In4.Cu" signal "GND1")
		(12 "In5.Cu" signal "IN1")
		(14 "In6.Cu" signal "GND2")
		(16 "In7.Cu" signal "IN2")
		(18 "In8.Cu" signal "GND3")
		(20 "In9.Cu" signal "IN3")
		(22 "In10.Cu" signal "GND4")
		(24 "In11.Cu" signal "IN4")
		(26 "In12.Cu" signal "GND5")
		(28 "In13.Cu" signal "IN5")
		(30 "In14.Cu" signal "GND6")
		(32 "In15.Cu" signal "IN6")
		(34 "In16.Cu" signal "GND7")
		(2 "B.Cu" signal "BOTTOM")
		(9 "F.Adhes" user "F.Adhesive")
		(11 "B.Adhes" user "B.Adhesive")
		(13 "F.Paste" user "Package Geometry/Pastemask Top")
		(15 "B.Paste" user "Package Geometry/Pastemask Bottom")
		(5 "F.SilkS" user "Ref Des/Silkscreen Top")
		(7 "B.SilkS" user "Ref Des/Silkscreen Bottom")
		(1 "F.Mask" user "Board Geometry/Soldermask Top")
		(3 "B.Mask" user "Board Geometry/Soldermask Bottom")
		(17 "Dwgs.User" user "User.Drawings")
		(19 "Cmts.User" user "User.Comments")
		(21 "Eco1.User" user "User.Eco1")
		(23 "Eco2.User" user "User.Eco2")
		(25 "Edge.Cuts" user "Board Geometry/Outline")
		(27 "Margin" user)
		(31 "F.CrtYd" user "Package Geometry/Place Bound Top")
		(29 "B.CrtYd" user "Package Geometry/Place Bound Bottom")
		(35 "F.Fab" user "Ref Des/Assembly Top")
		(33 "B.Fab" user "Ref Des/Assembly Bottom")
	)
	(footprint ""
		(layer "B.Cu")
		(at 204.373226 -361.988608 180)
		(property "Reference" "R494"
			(at 0 0 0)
			(layer "B.SilkS")
			(hide yes)
			(effects
				(font
					(size 1.27 1.27)
				)
				(justify mirror)
			)
		)
		(property "Value" ""
			(at 0 0 0)
			(layer "B.Fab")
			(effects
				(font
					(size 1.27 1.27)
				)
				(justify mirror)
			)
		)
		(duplicate_pad_numbers_are_jumpers no)
		(fp_line
			(start 0.7874 0.4064)
			(end 0.7874 -0.4064)
			(stroke
				(width 0.1524)
				(type default)
			)
			(layer "B.SilkS")
		)
		(fp_line
			(start 0.7874 -0.4064)
			(end -0.7874 -0.4064)
			(stroke
				(width 0.1524)
				(type default)
			)
			(layer "B.SilkS")
		)
		(fp_line
			(start -0.7874 0.4064)
			(end 0.7874 0.4064)
			(stroke
				(width 0.1524)
				(type default)
			)
			(layer "B.SilkS")
		)
		(fp_line
			(start -0.7874 -0.4064)
			(end -0.7874 0.4064)
			(stroke
				(width 0.1524)
				(type default)
			)
			(layer "B.SilkS")
		)
		(fp_line
			(start 0.67945 0.3048)
			(end 0.67945 -0.305054)
			(stroke
				(width 0.1)
				(type default)
			)
			(layer "B.Fab")
		)
		(fp_line
			(start 0.67945 -0.305054)
			(end 0.12065 -0.305054)
			(stroke
				(width 0.1)
				(type default)
			)
			(layer "B.Fab")
		)
		(fp_line
			(start 0.12065 0.3048)
			(end 0.67945 0.3048)
			(stroke
				(width 0.1)
				(type default)
			)
			(layer "B.Fab")
		)
		(fp_line
			(start 0.12065 0.2794)
			(end 0.12065 0.3048)
			(stroke
				(width 0.1)
				(type default)
			)
			(layer "B.Fab")
		)
		(fp_line
			(start 0.12065 -0.2794)
			(end -0.12065 -0.2794)
			(stroke
				(width 0.1)
				(type default)
			)
			(layer "B.Fab")
		)
		(fp_line
			(start 0.12065 -0.305054)
			(end 0.12065 -0.2794)
			(stroke
				(width 0.1)
				(type default)
			)
			(layer "B.Fab")
		)
		(fp_line
			(start -0.120396 0.3048)
			(end -0.120396 0.2794)
			(stroke
				(width 0.1)
				(type default)
			)
			(layer "B.Fab")
		)
		(fp_line
			(start -0.120396 0.2794)
			(end 0.12065 0.2794)
			(stroke
				(width 0.1)
				(type default)
			)
			(layer "B.Fab")
		)
		(fp_line
			(start -0.12065 -0.2794)
			(end -0.12065 -0.3048)
			(stroke
				(width 0.1)
				(type default)
			)
			(layer "B.Fab")
		)
		(fp_line
			(start -0.12065 -0.3048)
			(end -0.67945 -0.3048)
			(stroke
				(width 0.1)
				(type default)
			)
			(layer "B.Fab")
		)
		(fp_line
			(start -0.67945 0.3048)
			(end -0.120396 0.3048)
			(stroke
				(width 0.1)
				(type default)
			)
			(layer "B.Fab")
		)
		(fp_line
			(start -0.67945 -0.3048)
			(end -0.67945 0.3048)
			(stroke
				(width 0.1)
				(type default)
			)
			(layer "B.Fab")
		)
		(pad "1" smd circle
			(at 0.40005 0)
			(size 0 0)
			(layers "B.Cu" "B.Mask" "B.Paste")
			(net "P12V_STBY_FUSE")
		)
		(pad "2" smd circle
			(at -0.40005 0)
			(size 0 0)
			(layers "B.Cu" "B.Mask" "B.Paste")
			(net "HSC_P12V_EN")
		)
	)
	(footprint ""
		(layer "B.Cu")
		(at 61.722 -296.3926)
		(property "Reference" "C1107"
			(at 0 0 0)
			(layer "B.SilkS")
			(hide yes)
			(effects
				(font
					(size 1.27 1.27)
				)
				(justify mirror)
			)
		)
		(property "Value" ""
			(at 0 0 0)
			(layer "B.Fab")
			(effects
				(font
					(size 1.27 1.27)
				)
				(justify mirror)
			)
		)
		(duplicate_pad_numbers_are_jumpers no)
		(fp_line
			(start -0.299974 -0.150114)
			(end -0.299974 0.150114)
			(stroke
				(width 0.1)
				(type default)
			)
			(layer "B.Fab")
		)
		(fp_line
			(start -0.299974 0.150114)
			(end 0.299974 0.150114)
			(stroke
				(width 0.1)
				(type default)
			)
			(layer "B.Fab")
		)
		(fp_line
			(start 0.299974 -0.150114)
			(end -0.299974 -0.150114)
			(stroke
				(width 0.1)
				(type default)
			)
			(layer "B.Fab")
		)
		(fp_line
			(start 0.299974 0.150114)
			(end 0.299974 -0.150114)
			(stroke
				(width 0.1)
				(type default)
			)
			(layer "B.Fab")
		)
		(pad "1" smd rect
			(at 0.2667 0 180)
			(size 0.3048 0.381)
			(layers "B.Cu" "B.Mask" "B.Paste")
			(net "P0V8_PEX0")
		)
		(pad "2" smd rect
			(at -0.2667 0 180)
			(size 0.3048 0.381)
			(layers "B.Cu" "B.Mask" "B.Paste")
			(net "GND")
		)
	)
	(footprint ""
		(layer "B.Cu")
		(at 121.437654 -321.387978 -90)
		(property "Reference" "R6485"
			(at 0 0 90)
			(layer "B.SilkS")
			(hide yes)
			(effects
				(font
					(size 1.27 1.27)
				)
				(justify mirror)
			)
		)
		(property "Value" ""
			(at 0 0 90)
			(layer "B.Fab")
			(effects
				(font
					(size 1.27 1.27)
				)
				(justify mirror)
			)
		)
		(duplicate_pad_numbers_are_jumpers no)
		(fp_line
			(start -0.7874 0.4064)
			(end 0.7874 0.4064)
			(stroke
				(width 0.1524)
				(type default)
			)
			(layer "B.SilkS")
		)
		(fp_line
			(start 0.7874 0.4064)
			(end 0.7874 -0.4064)
			(stroke
				(width 0.1524)
				(type default)
			)
			(layer "B.SilkS")
		)
		(fp_line
			(start -0.7874 -0.4064)
			(end -0.7874 0.4064)
			(stroke
				(width 0.1524)
				(type default)
			)
			(layer "B.SilkS")
		)
		(fp_line
			(start 0.7874 -0.4064)
			(end -0.7874 -0.4064)
			(stroke
				(width 0.1524)
				(type default)
			)
			(layer "B.SilkS")
		)
		(fp_line
			(start -0.67945 0.3048)
			(end -0.120396 0.3048)
			(stroke
				(width 0.1)
				(type default)
			)
			(layer "B.Fab")
		)
		(fp_line
			(start -0.120396 0.3048)
			(end -0.120396 0.2794)
			(stroke
				(width 0.1)
				(type default)
			)
			(layer "B.Fab")
		)
		(fp_line
			(start 0.12065 0.3048)
			(end 0.67945 0.3048)
			(stroke
				(width 0.1)
				(type default)
			)
			(layer "B.Fab")
		)
		(fp_line
			(start 0.67945 0.3048)
			(end 0.67945 -0.305054)
			(stroke
				(width 0.1)
				(type default)
			)
			(layer "B.Fab")
		)
		(fp_line
			(start -0.120396 0.2794)
			(end 0.12065 0.2794)
			(stroke
				(width 0.1)
				(type default)
			)
			(layer "B.Fab")
		)
		(fp_line
			(start 0.12065 0.2794)
			(end 0.12065 0.3048)
			(stroke
				(width 0.1)
				(type default)
			)
			(layer "B.Fab")
		)
		(fp_line
			(start -0.12065 -0.2794)
			(end -0.12065 -0.3048)
			(stroke
				(width 0.1)
				(type default)
			)
			(layer "B.Fab")
		)
		(fp_line
			(start 0.12065 -0.2794)
			(end -0.12065 -0.2794)
			(stroke
				(width 0.1)
				(type default)
			)
			(layer "B.Fab")
		)
		(fp_line
			(start -0.67945 -0.3048)
			(end -0.67945 0.3048)
			(stroke
				(width 0.1)
				(type default)
			)
			(layer "B.Fab")
		)
		(fp_line
			(start -0.12065 -0.3048)
			(end -0.67945 -0.3048)
			(stroke
				(width 0.1)
				(type default)
			)
			(layer "B.Fab")
		)
		(fp_line
			(start 0.12065 -0.305054)
			(end 0.12065 -0.2794)
			(stroke
				(width 0.1)
				(type default)
			)
			(layer "B.Fab")
		)
		(fp_line
			(start 0.67945 -0.305054)
			(end 0.12065 -0.305054)
			(stroke
				(width 0.1)
				(type default)
			)
			(layer "B.Fab")
		)
		(pad "1" smd circle
			(at 0.40005 0 90)
			(size 0 0)
			(layers "B.Cu" "B.Mask" "B.Paste")
			(net "P0V8_SERDES_VDDA_PEX1")
		)
		(pad "2" smd circle
			(at -0.40005 0 90)
			(size 0 0)
			(layers "B.Cu" "B.Mask" "B.Paste")
			(net "P0V8_SERDES_VDDA_PEX1_C8")
		)
	)
	(footprint ""
		(layer "B.Cu")
		(at 362.459016 -319.545462 -90)
		(property "Reference" "L77"
			(at 0 0 90)
			(layer "B.SilkS")
			(hide yes)
			(effects
				(font
					(size 1.27 1.27)
				)
				(justify mirror)
			)
		)
		(property "Value" ""
			(at 0 0 90)
			(layer "B.Fab")
			(effects
				(font
					(size 1.27 1.27)
				)
				(justify mirror)
			)
		)
		(duplicate_pad_numbers_are_jumpers no)
		(fp_line
			(start 2.248154 4.9911)
			(end -0.653542 4.9911)
			(stroke
				(width 0.1524)
				(type default)
			)
			(layer "B.SilkS")
		)
		(fp_line
			(start 2.248154 1.961896)
			(end 2.248154 4.9911)
			(stroke
				(width 0.1524)
				(type default)
			)
			(layer "B.SilkS")
		)
		(fp_line
			(start -2.248154 -4.9911)
			(end 2.248154 -4.9911)
			(stroke
				(width 0.1524)
				(type default)
			)
			(layer "B.SilkS")
		)
		(fp_line
			(start 2.248154 -4.9911)
			(end 2.248154 -2.275332)
			(stroke
				(width 0.1524)
				(type default)
			)
			(layer "B.SilkS")
		)
		(fp_line
			(start -1.700022 0.899922)
			(end -1.700022 -0.899922)
			(stroke
				(width 0.1)
				(type default)
			)
			(layer "B.Fab")
		)
		(fp_line
			(start 1.700022 0.899922)
			(end -1.700022 0.899922)
			(stroke
				(width 0.1)
				(type default)
			)
			(layer "B.Fab")
		)
		(fp_line
			(start -1.700022 -0.899922)
			(end 1.700022 -0.899922)
			(stroke
				(width 0.1)
				(type default)
			)
			(layer "B.Fab")
		)
		(fp_line
			(start 1.700022 -0.899922)
			(end 1.700022 0.899922)
			(stroke
				(width 0.1)
				(type default)
			)
			(layer "B.Fab")
		)
		(pad "1" smd rect
			(at 1.575054 0 90)
			(size 1.1684 9.8044)
			(layers "B.Cu" "B.Mask" "B.Paste")
			(net "P0V8_PEX3")
		)
		(pad "2" smd rect
			(at -1.575054 0 90)
			(size 1.1684 9.8044)
			(layers "B.Cu" "B.Mask" "B.Paste")
			(net "P0V8_SERDES_VDDA_PEX3")
		)
	)
	(footprint ""
		(layer "B.Cu")
		(at 40.173656 -296.9514 180)
		(property "Reference" "R3294"
			(at 0 0 0)
			(layer "B.SilkS")
			(hide yes)
			(effects
				(font
					(size 1.27 1.27)
				)
				(justify mirror)
			)
		)
		(property "Value" ""
			(at 0 0 0)
			(layer "B.Fab")
			(effects
				(font
					(size 1.27 1.27)
				)
				(justify mirror)
			)
		)
		(duplicate_pad_numbers_are_jumpers no)
		(fp_line
			(start 0.7874 0.4064)
			(end 0.7874 -0.4064)
			(stroke
				(width 0.1524)
				(type default)
			)
			(layer "B.SilkS")
		)
		(fp_line
			(start 0.7874 -0.4064)
			(end -0.7874 -0.4064)
			(stroke
				(width 0.1524)
				(type default)
			)
			(layer "B.SilkS")
		)
		(fp_line
			(start -0.7874 0.4064)
			(end 0.7874 0.4064)
			(stroke
				(width 0.1524)
				(type default)
			)
			(layer "B.SilkS")
		)
		(fp_line
			(start -0.7874 -0.4064)
			(end -0.7874 0.4064)
			(stroke
				(width 0.1524)
				(type default)
			)
			(layer "B.SilkS")
		)
		(fp_line
			(start 0.67945 0.3048)
			(end 0.67945 -0.305054)
			(stroke
				(width 0.1)
				(type default)
			)
			(layer "B.Fab")
		)
		(fp_line
			(start 0.67945 -0.305054)
			(end 0.12065 -0.305054)
			(stroke
				(width 0.1)
				(type default)
			)
			(layer "B.Fab")
		)
		(fp_line
			(start 0.12065 0.3048)
			(end 0.67945 0.3048)
			(stroke
				(width 0.1)
				(type default)
			)
			(layer "B.Fab")
		)
		(fp_line
			(start 0.12065 0.2794)
			(end 0.12065 0.3048)
			(stroke
				(width 0.1)
				(type default)
			)
			(layer "B.Fab")
		)
		(fp_line
			(start 0.12065 -0.2794)
			(end -0.12065 -0.2794)
			(stroke
				(width 0.1)
				(type default)
			)
			(layer "B.Fab")
		)
		(fp_line
			(start 0.12065 -0.305054)
			(end 0.12065 -0.2794)
			(stroke
				(width 0.1)
				(type default)
			)
			(layer "B.Fab")
		)
		(fp_line
			(start -0.120396 0.3048)
			(end -0.120396 0.2794)
			(stroke
				(width 0.1)
				(type default)
			)
			(layer "B.Fab")
		)
		(fp_line
			(start -0.120396 0.2794)
			(end 0.12065 0.2794)
			(stroke
				(width 0.1)
				(type default)
			)
			(layer "B.Fab")
		)
		(fp_line
			(start -0.12065 -0.2794)
			(end -0.12065 -0.3048)
			(stroke
				(width 0.1)
				(type default)
			)
			(layer "B.Fab")
		)
		(fp_line
			(start -0.12065 -0.3048)
			(end -0.67945 -0.3048)
			(stroke
				(width 0.1)
				(type default)
			)
			(layer "B.Fab")
		)
		(fp_line
			(start -0.67945 0.3048)
			(end -0.120396 0.3048)
			(stroke
				(width 0.1)
				(type default)
			)
			(layer "B.Fab")
		)
		(fp_line
			(start -0.67945 -0.3048)
			(end -0.67945 0.3048)
			(stroke
				(width 0.1)
				(type default)
			)
			(layer "B.Fab")
		)
		(pad "1" smd circle
			(at 0.40005 0)
			(size 0 0)
			(layers "B.Cu" "B.Mask" "B.Paste")
			(net "SPI_PEX0_SDIO1_R")
		)
		(pad "2" smd circle
			(at -0.40005 0)
			(size 0 0)
			(layers "B.Cu" "B.Mask" "B.Paste")
			(net "SPI_PEX0_SDIO1")
		)
	)
	(footprint ""
		(layer "B.Cu")
		(at 69.149976 -301.124874)
		(property "Reference" "C2991"
			(at 0 0 0)
			(layer "B.SilkS")
			(hide yes)
			(effects
				(font
					(size 1.27 1.27)
				)
				(justify mirror)
			)
		)
		(property "Value" ""
			(at 0 0 0)
			(layer "B.Fab")
			(effects
				(font
					(size 1.27 1.27)
				)
				(justify mirror)
			)
		)
		(duplicate_pad_numbers_are_jumpers no)
		(fp_line
			(start -0.299974 -0.150114)
			(end -0.299974 0.150114)
			(stroke
				(width 0.1)
				(type default)
			)
			(layer "B.Fab")
		)
		(fp_line
			(start -0.299974 0.150114)
			(end 0.299974 0.150114)
			(stroke
				(width 0.1)
				(type default)
			)
			(layer "B.Fab")
		)
		(fp_line
			(start 0.299974 -0.150114)
			(end -0.299974 -0.150114)
			(stroke
				(width 0.1)
				(type default)
			)
			(layer "B.Fab")
		)
		(fp_line
			(start 0.299974 0.150114)
			(end 0.299974 -0.150114)
			(stroke
				(width 0.1)
				(type default)
			)
			(layer "B.Fab")
		)
		(pad "1" smd rect
			(at 0.2667 0 180)
			(size 0.3048 0.381)
			(layers "B.Cu" "B.Mask" "B.Paste")
			(net "P1V8_PEX")
		)
		(pad "2" smd rect
			(at -0.2667 0 180)
			(size 0.3048 0.381)
			(layers "B.Cu" "B.Mask" "B.Paste")
			(net "GND")
		)
	)
	(footprint ""
		(layer "B.Cu")
		(at 47.77486 -294.132 -90)
		(property "Reference" "C3047"
			(at 0 0 90)
			(layer "B.SilkS")
			(hide yes)
			(effects
				(font
					(size 1.27 1.27)
				)
				(justify mirror)
			)
		)
		(property "Value" ""
			(at 0 0 90)
			(layer "B.Fab")
			(effects
				(font
					(size 1.27 1.27)
				)
				(justify mirror)
			)
		)
		(duplicate_pad_numbers_are_jumpers no)
		(fp_line
			(start -0.299974 0.150114)
			(end 0.299974 0.150114)
			(stroke
				(width 0.1)
				(type default)
			)
			(layer "B.Fab")
		)
		(fp_line
			(start 0.299974 0.150114)
			(end 0.299974 -0.150114)
			(stroke
				(width 0.1)
				(type default)
			)
			(layer "B.Fab")
		)
		(fp_line
			(start -0.299974 -0.150114)
			(end -0.299974 0.150114)
			(stroke
				(width 0.1)
				(type default)
			)
			(layer "B.Fab")
		)
		(fp_line
			(start 0.299974 -0.150114)
			(end -0.299974 -0.150114)
			(stroke
				(width 0.1)
				(type default)
			)
			(layer "B.Fab")
		)
		(pad "1" smd rect
			(at 0.2667 0 90)
			(size 0.3048 0.381)
			(layers "B.Cu" "B.Mask" "B.Paste")
			(net "PCEPLL5_VDDA18_PEX0")
		)
		(pad "2" smd rect
			(at -0.2667 0 90)
			(size 0.3048 0.381)
			(layers "B.Cu" "B.Mask" "B.Paste")
			(net "GND")
		)
	)
	(footprint ""
		(layer "B.Cu")
		(at 224.81794 -197.788022 -90)
		(property "Reference" "R1023"
			(at 0 0 90)
			(layer "B.SilkS")
			(hide yes)
			(effects
				(font
					(size 1.27 1.27)
				)
				(justify mirror)
			)
		)
		(property "Value" ""
			(at 0 0 90)
			(layer "B.Fab")
			(effects
				(font
					(size 1.27 1.27)
				)
				(justify mirror)
			)
		)
		(duplicate_pad_numbers_are_jumpers no)
		(fp_line
			(start -0.7874 0.4064)
			(end 0.7874 0.4064)
			(stroke
				(width 0.1524)
				(type default)
			)
			(layer "B.SilkS")
		)
		(fp_line
			(start 0.7874 0.4064)
			(end 0.7874 -0.4064)
			(stroke
				(width 0.1524)
				(type default)
			)
			(layer "B.SilkS")
		)
		(fp_line
			(start -0.7874 -0.4064)
			(end -0.7874 0.4064)
			(stroke
				(width 0.1524)
				(type default)
			)
			(layer "B.SilkS")
		)
		(fp_line
			(start 0.7874 -0.4064)
			(end -0.7874 -0.4064)
			(stroke
				(width 0.1524)
				(type default)
			)
			(layer "B.SilkS")
		)
		(fp_line
			(start -0.67945 0.3048)
			(end -0.120396 0.3048)
			(stroke
				(width 0.1)
				(type default)
			)
			(layer "B.Fab")
		)
		(fp_line
			(start -0.120396 0.3048)
			(end -0.120396 0.2794)
			(stroke
				(width 0.1)
				(type default)
			)
			(layer "B.Fab")
		)
		(fp_line
			(start 0.12065 0.3048)
			(end 0.67945 0.3048)
			(stroke
				(width 0.1)
				(type default)
			)
			(layer "B.Fab")
		)
		(fp_line
			(start 0.67945 0.3048)
			(end 0.67945 -0.305054)
			(stroke
				(width 0.1)
				(type default)
			)
			(layer "B.Fab")
		)
		(fp_line
			(start -0.120396 0.2794)
			(end 0.12065 0.2794)
			(stroke
				(width 0.1)
				(type default)
			)
			(layer "B.Fab")
		)
		(fp_line
			(start 0.12065 0.2794)
			(end 0.12065 0.3048)
			(stroke
				(width 0.1)
				(type default)
			)
			(layer "B.Fab")
		)
		(fp_line
			(start -0.12065 -0.2794)
			(end -0.12065 -0.3048)
			(stroke
				(width 0.1)
				(type default)
			)
			(layer "B.Fab")
		)
		(fp_line
			(start 0.12065 -0.2794)
			(end -0.12065 -0.2794)
			(stroke
				(width 0.1)
				(type default)
			)
			(layer "B.Fab")
		)
		(fp_line
			(start -0.67945 -0.3048)
			(end -0.67945 0.3048)
			(stroke
				(width 0.1)
				(type default)
			)
			(layer "B.Fab")
		)
		(fp_line
			(start -0.12065 -0.3048)
			(end -0.67945 -0.3048)
			(stroke
				(width 0.1)
				(type default)
			)
			(layer "B.Fab")
		)
		(fp_line
			(start 0.12065 -0.305054)
			(end 0.12065 -0.2794)
			(stroke
				(width 0.1)
				(type default)
			)
			(layer "B.Fab")
		)
		(fp_line
			(start 0.67945 -0.305054)
			(end 0.12065 -0.305054)
			(stroke
				(width 0.1)
				(type default)
			)
			(layer "B.Fab")
		)
		(pad "1" smd circle
			(at 0.40005 0 90)
			(size 0 0)
			(layers "B.Cu" "B.Mask" "B.Paste")
			(net "SPI_BIC1_CLK_R")
		)
		(pad "2" smd circle
			(at -0.40005 0 90)
			(size 0 0)
			(layers "B.Cu" "B.Mask" "B.Paste")
			(net "SPI_BIC1_CLK_R5")
		)
	)
	(footprint ""
		(layer "B.Cu")
		(at 168.150032 -301.599854 -90)
		(property "Reference" "C1429"
			(at 0 0 90)
			(layer "B.SilkS")
			(hide yes)
			(effects
				(font
					(size 1.27 1.27)
				)
				(justify mirror)
			)
		)
		(property "Value" ""
			(at 0 0 90)
			(layer "B.Fab")
			(effects
				(font
					(size 1.27 1.27)
				)
				(justify mirror)
			)
		)
		(duplicate_pad_numbers_are_jumpers no)
		(fp_line
			(start -0.299974 0.150114)
			(end 0.299974 0.150114)
			(stroke
				(width 0.1)
				(type default)
			)
			(layer "B.Fab")
		)
		(fp_line
			(start 0.299974 0.150114)
			(end 0.299974 -0.150114)
			(stroke
				(width 0.1)
				(type default)
			)
			(layer "B.Fab")
		)
		(fp_line
			(start -0.299974 -0.150114)
			(end -0.299974 0.150114)
			(stroke
				(width 0.1)
				(type default)
			)
			(layer "B.Fab")
		)
		(fp_line
			(start 0.299974 -0.150114)
			(end -0.299974 -0.150114)
			(stroke
				(width 0.1)
				(type default)
			)
			(layer "B.Fab")
		)
		(pad "1" smd rect
			(at 0.2667 0 90)
			(size 0.3048 0.381)
			(layers "B.Cu" "B.Mask" "B.Paste")
			(net "P0V8_SERDES_VDDA_PEX1")
		)
		(pad "2" smd rect
			(at -0.2667 0 90)
			(size 0.3048 0.381)
			(layers "B.Cu" "B.Mask" "B.Paste")
			(net "GND")
		)
	)
)
